# T6G (Grand Teton) — schematic netlist excerpt (pin names and nets, part order shuffled) for the footprints in the layout excerpt that follows; sources: Cadence DE-HDL packaged netlist, KiCad conversion of 04192023_DAF0TMB3IC0_F0TG_MB_C_brd_V02_OCP.brd

Y6000  Q_XTAL_4P_13BI_24GND  24MHZ MISC  pkg X_7MXA  page 179
  X1  = XTAL_USB_CPU0_HUB2_XIN
  G1  = GND
  X2  = XTAL_USB_CPU0_HUB2_XOUT
  G2  = GND

C1510  Q_CAP  33PF 50V 5% NPO  pkg 0402  page 172 : A = JTAG_TCK ; B = GND

(kicad_pcb
	(version 20260206)
	(generator "pcbnew")
	(generator_version "10.0")
	(general
		(thickness 1.6)
		(legacy_teardrops no)
	)
	(paper "A4")
	(title_block
		(title "04192023_DAF0TMB3IC0_F0TG_MB_C_brd_V02_OCP.brd")
		(comment 1 "Grand Teton / footprints 1754-1755 of 8354")
	)
	(layers
		(0 "F.Cu" signal "TOP")
		(4 "In1.Cu" signal "GND")
		(6 "In2.Cu" signal "IN1")
		(8 "In3.Cu" signal "GND1")
		(10 "In4.Cu" signal "IN2")
		(12 "In5.Cu" signal "GND2")
		(14 "In6.Cu" signal "IN3")
		(16 "In7.Cu" signal "GND3")
		(18 "In8.Cu" signal "VCC")
		(20 "In9.Cu" signal "VCC1")
		(22 "In10.Cu" signal "GND4")
		(24 "In11.Cu" signal "IN4")
		(26 "In12.Cu" signal "GND5")
		(28 "In13.Cu" signal "IN5")
		(30 "In14.Cu" signal "GND6")
		(32 "In15.Cu" signal "IN6")
		(34 "In16.Cu" signal "GND7")
		(2 "B.Cu" signal "BOTTOM")
		(9 "F.Adhes" user "F.Adhesive")
		(11 "B.Adhes" user "B.Adhesive")
		(13 "F.Paste" user "Package Geometry/Pastemask Top")
		(15 "B.Paste" user "Package Geometry/Pastemask Bottom")
		(5 "F.SilkS" user "Ref Des/Silkscreen Top")
		(7 "B.SilkS" user "Ref Des/Silkscreen Bottom")
		(1 "F.Mask" user "Board Geometry/Soldermask Top")
		(3 "B.Mask" user "Board Geometry/Soldermask Bottom")
		(17 "Dwgs.User" user "User.Drawings")
		(19 "Cmts.User" user "User.Comments")
		(21 "Eco1.User" user "User.Eco1")
		(23 "Eco2.User" user "User.Eco2")
		(25 "Edge.Cuts" user "Board Geometry/Outline")
		(27 "Margin" user)
		(31 "F.CrtYd" user "Package Geometry/Place Bound Top")
		(29 "B.CrtYd" user "Package Geometry/Place Bound Bottom")
		(35 "F.Fab" user "Ref Des/Assembly Top")
		(33 "B.Fab" user "Ref Des/Assembly Bottom")
	)
	(footprint ""
		(layer "F.Cu")
		(at 288.26587 -96.655382)
		(property "Reference" "C1510"
			(at 0 0 0)
			(layer "F.SilkS")
			(hide yes)
			(effects
				(font
					(size 1.27 1.27)
				)
			)
		)
		(property "Value" ""
			(at 0 0 0)
			(layer "F.Fab")
			(effects
				(font
					(size 1.27 1.27)
				)
			)
		)
		(duplicate_pad_numbers_are_jumpers no)
		(fp_line
			(start -0.7874 -0.4064)
			(end 0.7874 -0.4064)
			(stroke
				(width 0.1524)
				(type default)
			)
			(layer "F.SilkS")
		)
		(fp_line
			(start -0.7874 0.4064)
			(end -0.7874 -0.4064)
			(stroke
				(width 0.1524)
				(type default)
			)
			(layer "F.SilkS")
		)
		(fp_line
			(start 0.7874 -0.4064)
			(end 0.7874 0.4064)
			(stroke
				(width 0.1524)
				(type default)
			)
			(layer "F.SilkS")
		)
		(fp_line
			(start 0.7874 0.4064)
			(end -0.7874 0.4064)
			(stroke
				(width 0.1524)
				(type default)
			)
			(layer "F.SilkS")
		)
		(fp_line
			(start -0.67945 -0.305054)
			(end -0.12065 -0.305054)
			(stroke
				(width 0.1)
				(type default)
			)
			(layer "F.Fab")
		)
		(fp_line
			(start -0.67945 0.3048)
			(end -0.67945 -0.305054)
			(stroke
				(width 0.1)
				(type default)
			)
			(layer "F.Fab")
		)
		(fp_line
			(start -0.12065 -0.305054)
			(end -0.12065 -0.2794)
			(stroke
				(width 0.1)
				(type default)
			)
			(layer "F.Fab")
		)
		(fp_line
			(start -0.12065 -0.2794)
			(end 0.12065 -0.2794)
			(stroke
				(width 0.1)
				(type default)
			)
			(layer "F.Fab")
		)
		(fp_line
			(start -0.12065 0.2794)
			(end -0.12065 0.3048)
			(stroke
				(width 0.1)
				(type default)
			)
			(layer "F.Fab")
		)
		(fp_line
			(start -0.12065 0.3048)
			(end -0.67945 0.3048)
			(stroke
				(width 0.1)
				(type default)
			)
			(layer "F.Fab")
		)
		(fp_line
			(start 0.120396 0.2794)
			(end -0.12065 0.2794)
			(stroke
				(width 0.1)
				(type default)
			)
			(layer "F.Fab")
		)
		(fp_line
			(start 0.120396 0.3048)
			(end 0.120396 0.2794)
			(stroke
				(width 0.1)
				(type default)
			)
			(layer "F.Fab")
		)
		(fp_line
			(start 0.12065 -0.3048)
			(end 0.67945 -0.3048)
			(stroke
				(width 0.1)
				(type default)
			)
			(layer "F.Fab")
		)
		(fp_line
			(start 0.12065 -0.2794)
			(end 0.12065 -0.3048)
			(stroke
				(width 0.1)
				(type default)
			)
			(layer "F.Fab")
		)
		(fp_line
			(start 0.67945 -0.3048)
			(end 0.67945 0.3048)
			(stroke
				(width 0.1)
				(type default)
			)
			(layer "F.Fab")
		)
		(fp_line
			(start 0.67945 0.3048)
			(end 0.120396 0.3048)
			(stroke
				(width 0.1)
				(type default)
			)
			(layer "F.Fab")
		)
		(pad "1" smd circle
			(at -0.40005 0)
			(size 0 0)
			(layers "F.Cu" "F.Mask" "F.Paste")
			(net "JTAG_TCK")
		)
		(pad "2" smd circle
			(at 0.40005 0)
			(size 0 0)
			(layers "F.Cu" "F.Mask" "F.Paste")
			(net "GND")
		)
	)
	(footprint ""
		(layer "F.Cu")
		(at 106.250486 -22.271482 180)
		(property "Reference" "Y6000"
			(at 2.285492 -3.005836 0)
			(unlocked yes)
			(layer "F.SilkS")
			(effects
				(font
					(size 0.7874 0.5842)
					(thickness 0.1524)
				)
				(justify left)
			)
		)
		(property "Value" ""
			(at 0 0 180)
			(layer "F.Fab")
			(effects
				(font
					(size 1.27 1.27)
				)
			)
		)
		(duplicate_pad_numbers_are_jumpers no)
		(fp_line
			(start 1.6002 1.9558)
			(end -1.6002 1.9558)
			(stroke
				(width 0.1524)
				(type default)
			)
			(layer "F.SilkS")
		)
		(fp_line
			(start 1.6002 -1.9558)
			(end 1.6002 1.9558)
			(stroke
				(width 0.1524)
				(type default)
			)
			(layer "F.SilkS")
		)
		(fp_line
			(start -1.6002 1.9558)
			(end -1.6002 -1.9558)
			(stroke
				(width 0.1524)
				(type default)
			)
			(layer "F.SilkS")
		)
		(fp_line
			(start -1.6002 -1.9558)
			(end 1.6002 -1.9558)
			(stroke
				(width 0.1524)
				(type default)
			)
			(layer "F.SilkS")
		)
		(fp_poly
			(pts
				(xy -2.88036 -0.26416) (xy -2.88036 -1.33096) (xy -1.78816 -0.74676)
			)
			(stroke
				(width 0)
				(type default)
			)
			(fill yes)
			(layer "F.SilkS")
		)
		(fp_line
			(start 1.299972 1.649984)
			(end -1.299972 1.649984)
			(stroke
				(width 0.1)
				(type default)
			)
			(layer "F.Fab")
		)
		(fp_line
			(start 1.299972 -1.649984)
			(end 1.299972 1.649984)
			(stroke
				(width 0.1)
				(type default)
			)
			(layer "F.Fab")
		)
		(fp_line
			(start -1.299972 1.649984)
			(end -1.299972 -1.649984)
			(stroke
				(width 0.1)
				(type default)
			)
			(layer "F.Fab")
		)
		(fp_line
			(start -1.299972 -1.649984)
			(end 1.299972 -1.649984)
			(stroke
				(width 0.1)
				(type default)
			)
			(layer "F.Fab")
		)
		(fp_poly
			(pts
				(xy -1.7145 -1.0668) (xy -2.8067 -1.651) (xy -2.8067 -0.5842)
			)
			(stroke
				(width 0)
				(type default)
			)
			(fill yes)
			(layer "F.Fab")
		)
		(pad "1" smd rect
			(at -0.849884 -1.100074 180)
			(size 1.2192 1.4224)
			(layers "F.Cu" "F.Mask" "F.Paste")
			(net "XTAL_USB_CPU0_HUB2_XIN")
		)
		(pad "2" smd rect
			(at -0.849884 1.100074 180)
			(size 1.2192 1.4224)
			(layers "F.Cu" "F.Mask" "F.Paste")
			(net "GND")
		)
		(pad "3" smd rect
			(at 0.849884 1.100074 180)
			(size 1.2192 1.4224)
			(layers "F.Cu" "F.Mask" "F.Paste")
			(net "XTAL_USB_CPU0_HUB2_XOUT")
		)
		(pad "4" smd rect
			(at 0.849884 -1.100074 180)
			(size 1.2192 1.4224)
			(layers "F.Cu" "F.Mask" "F.Paste")
			(net "GND")
		)
	)
)
